# S9S_MB_2U (Grand Teton) — schematic netlist excerpt (pin names and nets, part order shuffled) for the footprints in the layout excerpt that follows; sources: Cadence DE-HDL packaged netlist, KiCad conversion of 03242023_DA0F0TMBIJ0_F0T_Motherboard_J_brd_V01_OCP.brd

R817  Q_RES  0 5% CHIP  pkg 0402LF  page 130 : A = RST_PLD_CPU1_DRAM_CD_N ; B = RST_M_CD_CPU1_FPGA_N
C389  Q_CAP  47UF 4V 20% X6S  pkg C0805  page 75 : A = PVCCIN_CPU0 ; B = GND
C1296  Q_CAP  1000PF 50V 5% X7R  pkg 0402  page 282 : A = PWRGD_PVNN_MAIN_CPU0 ; B = GND

(kicad_pcb
	(version 20260206)
	(generator "pcbnew")
	(generator_version "10.0")
	(general
		(thickness 1.6)
		(legacy_teardrops no)
	)
	(paper "A4")
	(title_block
		(title "03242023_DA0F0TMBIJ0_F0T_Motherboard_J_brd_V01_OCP.brd")
		(comment 1 "Grand Teton / footprints 4208-4210 of 6105")
	)
	(layers
		(0 "F.Cu" signal "TOP")
		(4 "In1.Cu" signal "GND")
		(6 "In2.Cu" signal "IN1")
		(8 "In3.Cu" signal "GND1")
		(10 "In4.Cu" signal "IN2")
		(12 "In5.Cu" signal "GND2")
		(14 "In6.Cu" signal "IN3")
		(16 "In7.Cu" signal "GND3")
		(18 "In8.Cu" signal "VCC")
		(20 "In9.Cu" signal "VCC1")
		(22 "In10.Cu" signal "GND4")
		(24 "In11.Cu" signal "IN4")
		(26 "In12.Cu" signal "GND5")
		(28 "In13.Cu" signal "IN5")
		(30 "In14.Cu" signal "GND6")
		(32 "In15.Cu" signal "IN6")
		(34 "In16.Cu" signal "GND7")
		(2 "B.Cu" signal "BOTTOM")
		(9 "F.Adhes" user "F.Adhesive")
		(11 "B.Adhes" user "B.Adhesive")
		(13 "F.Paste" user "Package Geometry/Pastemask Top")
		(15 "B.Paste" user "Package Geometry/Pastemask Bottom")
		(5 "F.SilkS" user "Ref Des/Silkscreen Top")
		(7 "B.SilkS" user "Ref Des/Silkscreen Bottom")
		(1 "F.Mask" user "Board Geometry/Soldermask Top")
		(3 "B.Mask" user "Board Geometry/Soldermask Bottom")
		(17 "Dwgs.User" user "User.Drawings")
		(19 "Cmts.User" user "User.Comments")
		(21 "Eco1.User" user "User.Eco1")
		(23 "Eco2.User" user "User.Eco2")
		(25 "Edge.Cuts" user "Board Geometry/Outline")
		(27 "Margin" user)
		(31 "F.CrtYd" user "Package Geometry/Place Bound Top")
		(29 "B.CrtYd" user "Package Geometry/Place Bound Bottom")
		(35 "F.Fab" user "Ref Des/Assembly Top")
		(33 "B.Fab" user "Ref Des/Assembly Bottom")
	)
	(footprint ""
		(layer "B.Cu")
		(at 26.359866 -193.152776 -90)
		(property "Reference" "R817"
			(at 0 0 90)
			(layer "B.SilkS")
			(hide yes)
			(effects
				(font
					(size 1.27 1.27)
				)
				(justify mirror)
			)
		)
		(property "Value" ""
			(at 0 0 90)
			(layer "B.Fab")
			(effects
				(font
					(size 1.27 1.27)
				)
				(justify mirror)
			)
		)
		(duplicate_pad_numbers_are_jumpers no)
		(fp_line
			(start -0.7874 0.4064)
			(end 0.7874 0.4064)
			(stroke
				(width 0.1524)
				(type default)
			)
			(layer "B.SilkS")
		)
		(fp_line
			(start 0.7874 0.4064)
			(end 0.7874 -0.4064)
			(stroke
				(width 0.1524)
				(type default)
			)
			(layer "B.SilkS")
		)
		(fp_line
			(start -0.7874 -0.4064)
			(end -0.7874 0.4064)
			(stroke
				(width 0.1524)
				(type default)
			)
			(layer "B.SilkS")
		)
		(fp_line
			(start 0.7874 -0.4064)
			(end -0.7874 -0.4064)
			(stroke
				(width 0.1524)
				(type default)
			)
			(layer "B.SilkS")
		)
		(fp_line
			(start -0.67945 0.3048)
			(end -0.120396 0.3048)
			(stroke
				(width 0.1)
				(type default)
			)
			(layer "B.Fab")
		)
		(fp_line
			(start -0.120396 0.3048)
			(end -0.120396 0.2794)
			(stroke
				(width 0.1)
				(type default)
			)
			(layer "B.Fab")
		)
		(fp_line
			(start 0.12065 0.3048)
			(end 0.67945 0.3048)
			(stroke
				(width 0.1)
				(type default)
			)
			(layer "B.Fab")
		)
		(fp_line
			(start 0.67945 0.3048)
			(end 0.67945 -0.305054)
			(stroke
				(width 0.1)
				(type default)
			)
			(layer "B.Fab")
		)
		(fp_line
			(start -0.120396 0.2794)
			(end 0.12065 0.2794)
			(stroke
				(width 0.1)
				(type default)
			)
			(layer "B.Fab")
		)
		(fp_line
			(start 0.12065 0.2794)
			(end 0.12065 0.3048)
			(stroke
				(width 0.1)
				(type default)
			)
			(layer "B.Fab")
		)
		(fp_line
			(start -0.12065 -0.2794)
			(end -0.12065 -0.3048)
			(stroke
				(width 0.1)
				(type default)
			)
			(layer "B.Fab")
		)
		(fp_line
			(start 0.12065 -0.2794)
			(end -0.12065 -0.2794)
			(stroke
				(width 0.1)
				(type default)
			)
			(layer "B.Fab")
		)
		(fp_line
			(start -0.67945 -0.3048)
			(end -0.67945 0.3048)
			(stroke
				(width 0.1)
				(type default)
			)
			(layer "B.Fab")
		)
		(fp_line
			(start -0.12065 -0.3048)
			(end -0.67945 -0.3048)
			(stroke
				(width 0.1)
				(type default)
			)
			(layer "B.Fab")
		)
		(fp_line
			(start 0.12065 -0.305054)
			(end 0.12065 -0.2794)
			(stroke
				(width 0.1)
				(type default)
			)
			(layer "B.Fab")
		)
		(fp_line
			(start 0.67945 -0.305054)
			(end 0.12065 -0.305054)
			(stroke
				(width 0.1)
				(type default)
			)
			(layer "B.Fab")
		)
		(pad "1" smd circle
			(at 0.40005 0 90)
			(size 0 0)
			(layers "B.Cu" "B.Mask" "B.Paste")
			(net "RST_PLD_CPU1_DRAM_CD_N")
		)
		(pad "2" smd circle
			(at -0.40005 0 90)
			(size 0 0)
			(layers "B.Cu" "B.Mask" "B.Paste")
			(net "RST_M_CD_CPU1_FPGA_N")
		)
	)
	(footprint ""
		(layer "B.Cu")
		(at 355.397308 -248.498106 -90)
		(property "Reference" "C389"
			(at 0 0 90)
			(layer "B.SilkS")
			(hide yes)
			(effects
				(font
					(size 1.27 1.27)
				)
				(justify mirror)
			)
		)
		(property "Value" ""
			(at 0 0 90)
			(layer "B.Fab")
			(effects
				(font
					(size 1.27 1.27)
				)
				(justify mirror)
			)
		)
		(duplicate_pad_numbers_are_jumpers no)
		(fp_line
			(start -1.524 0.762)
			(end 1.524 0.762)
			(stroke
				(width 0.1524)
				(type default)
			)
			(layer "B.SilkS")
		)
		(fp_line
			(start 1.524 0.762)
			(end 1.524 -0.762)
			(stroke
				(width 0.1524)
				(type default)
			)
			(layer "B.SilkS")
		)
		(fp_line
			(start -1.524 -0.762)
			(end -1.524 0.762)
			(stroke
				(width 0.1524)
				(type default)
			)
			(layer "B.SilkS")
		)
		(fp_line
			(start 1.524 -0.762)
			(end -1.524 -0.762)
			(stroke
				(width 0.1524)
				(type default)
			)
			(layer "B.SilkS")
		)
		(fp_line
			(start -1.1049 0.724916)
			(end -1.1049 -0.724916)
			(stroke
				(width 0.1)
				(type default)
			)
			(layer "B.Fab")
		)
		(fp_line
			(start 1.1049 0.724916)
			(end -1.1049 0.724916)
			(stroke
				(width 0.1)
				(type default)
			)
			(layer "B.Fab")
		)
		(fp_line
			(start -1.1049 -0.724916)
			(end 1.1049 -0.724916)
			(stroke
				(width 0.1)
				(type default)
			)
			(layer "B.Fab")
		)
		(fp_line
			(start 1.1049 -0.724916)
			(end 1.1049 0.724916)
			(stroke
				(width 0.1)
				(type default)
			)
			(layer "B.Fab")
		)
		(pad "1" smd rect
			(at 0.889 0 270)
			(size 1.016 1.27)
			(layers "B.Cu" "B.Mask" "B.Paste")
			(net "PVCCIN_CPU0")
		)
		(pad "2" smd rect
			(at -0.889 0 270)
			(size 1.016 1.27)
			(layers "B.Cu" "B.Mask" "B.Paste")
			(net "GND")
		)
	)
	(footprint ""
		(layer "B.Cu")
		(at 433.297584 -179.818538 90)
		(property "Reference" "C1296"
			(at 0 0 90)
			(layer "B.SilkS")
			(hide yes)
			(effects
				(font
					(size 1.27 1.27)
				)
				(justify mirror)
			)
		)
		(property "Value" ""
			(at 0 0 90)
			(layer "B.Fab")
			(effects
				(font
					(size 1.27 1.27)
				)
				(justify mirror)
			)
		)
		(duplicate_pad_numbers_are_jumpers no)
		(fp_line
			(start 0.7874 -0.4064)
			(end -0.7874 -0.4064)
			(stroke
				(width 0.1524)
				(type default)
			)
			(layer "B.SilkS")
		)
		(fp_line
			(start -0.7874 -0.4064)
			(end -0.7874 0.4064)
			(stroke
				(width 0.1524)
				(type default)
			)
			(layer "B.SilkS")
		)
		(fp_line
			(start 0.7874 0.4064)
			(end 0.7874 -0.4064)
			(stroke
				(width 0.1524)
				(type default)
			)
			(layer "B.SilkS")
		)
		(fp_line
			(start -0.7874 0.4064)
			(end 0.7874 0.4064)
			(stroke
				(width 0.1524)
				(type default)
			)
			(layer "B.SilkS")
		)
		(fp_line
			(start 0.67945 -0.305054)
			(end 0.12065 -0.305054)
			(stroke
				(width 0.1)
				(type default)
			)
			(layer "B.Fab")
		)
		(fp_line
			(start 0.12065 -0.305054)
			(end 0.12065 -0.2794)
			(stroke
				(width 0.1)
				(type default)
			)
			(layer "B.Fab")
		)
		(fp_line
			(start -0.12065 -0.3048)
			(end -0.67945 -0.3048)
			(stroke
				(width 0.1)
				(type default)
			)
			(layer "B.Fab")
		)
		(fp_line
			(start -0.67945 -0.3048)
			(end -0.67945 0.3048)
			(stroke
				(width 0.1)
				(type default)
			)
			(layer "B.Fab")
		)
		(fp_line
			(start 0.12065 -0.2794)
			(end -0.12065 -0.2794)
			(stroke
				(width 0.1)
				(type default)
			)
			(layer "B.Fab")
		)
		(fp_line
			(start -0.12065 -0.2794)
			(end -0.12065 -0.3048)
			(stroke
				(width 0.1)
				(type default)
			)
			(layer "B.Fab")
		)
		(fp_line
			(start 0.12065 0.2794)
			(end 0.12065 0.3048)
			(stroke
				(width 0.1)
				(type default)
			)
			(layer "B.Fab")
		)
		(fp_line
			(start -0.120396 0.2794)
			(end 0.12065 0.2794)
			(stroke
				(width 0.1)
				(type default)
			)
			(layer "B.Fab")
		)
		(fp_line
			(start 0.67945 0.3048)
			(end 0.67945 -0.305054)
			(stroke
				(width 0.1)
				(type default)
			)
			(layer "B.Fab")
		)
		(fp_line
			(start 0.12065 0.3048)
			(end 0.67945 0.3048)
			(stroke
				(width 0.1)
				(type default)
			)
			(layer "B.Fab")
		)
		(fp_line
			(start -0.120396 0.3048)
			(end -0.120396 0.2794)
			(stroke
				(width 0.1)
				(type default)
			)
			(layer "B.Fab")
		)
		(fp_line
			(start -0.67945 0.3048)
			(end -0.120396 0.3048)
			(stroke
				(width 0.1)
				(type default)
			)
			(layer "B.Fab")
		)
		(pad "1" smd circle
			(at 0.40005 0 270)
			(size 0 0)
			(layers "B.Cu" "B.Mask" "B.Paste")
			(net "PWRGD_PVNN_MAIN_CPU0")
		)
		(pad "2" smd circle
			(at -0.40005 0 270)
			(size 0 0)
			(layers "B.Cu" "B.Mask" "B.Paste")
			(net "GND")
		)
	)
)
